(kicad_pcb
	(version 20221018)
	(generator pcbnew)
	(general
    (thickness 1.7403)
  )
	(paper "A4")
	(title_block
    (title "Data Center RDIMM DDR4 Tester")
    (date "2024-09-30")
    (rev "1.2.4")
		(comment 9 "footprint 571 of 690 (J5), pads 215-320 of 404")
	)
	(layers
    (0 "F.Cu" signal)
    (1 "In1.Cu" power)
    (2 "In2.Cu" signal)
    (3 "In3.Cu" power)
    (4 "In4.Cu" power)
    (5 "In5.Cu" signal)
    (6 "In6.Cu" power)
    (7 "In7.Cu" signal)
    (8 "In8.Cu" power)
    (9 "In9.Cu" signal)
    (10 "In10.Cu" power)
    (31 "B.Cu" signal)
    (32 "B.Adhes" user "B.Adhesive")
    (33 "F.Adhes" user "F.Adhesive")
    (34 "B.Paste" user)
    (35 "F.Paste" user)
    (36 "B.SilkS" user "B.Silkscreen")
    (37 "F.SilkS" user "F.Silkscreen")
    (38 "B.Mask" user)
    (39 "F.Mask" user)
    (40 "Dwgs.User" user "User.Drawings")
    (41 "Cmts.User" user "User.Comments")
    (42 "Eco1.User" user "User.Eco1")
    (43 "Eco2.User" user "User.Eco2")
    (44 "Edge.Cuts" user)
    (45 "Margin" user)
    (46 "B.CrtYd" user "B.Courtyard")
    (47 "F.CrtYd" user "F.Courtyard")
    (48 "B.Fab" user)
    (49 "F.Fab" user)
  )
	(footprint "data-center-rdimm-ddr4-tester-footprints:FMC_SAMTEC_ASP-134486-01"
    (layer "B.Cu")
    (at 251 100 90)
    (descr "VITA 57.1 FMC – SEARAY™ HPC")
    (property "Author" "Antmicro")
    (property "License" "Apache-2.0")
    (property "MPN" "ASP-134486-01")
    (property "Manufacturer" "Samtec")
    (property "Sheetfile" "fmc_hpc.kicad_sch")
    (property "Sheetname" "FMC HPC")
    (property "ki_description" "400-pole 10-row 1.27mm Female FMC HPC Connector with gold-plated copper alloy contacts. ")
    (attr smd)
    (fp_text reference "J5" (at -28.4 4.01 270) (layer "B.SilkS")
        (effects (font (size 0.7 0.7) (thickness 0.15)) (justify left bottom mirror))
    )
    (fp_text value "ASP-134486-01" (at 0 -7.9 270) (layer "B.Fab") hide
        (effects (font (size 0.7 0.7) (thickness 0.15)) (justify left bottom mirror))
    )
    (pad "F11" smd circle (at -12.065 -0.634 270) (size 0.64 0.64) (layers "B.Cu" "B.Mask")
      (net 424 "unconnected-(J5C-HA08--PadF11)") (pinfunction "HA08-") (pintype "passive+no_connect"))
    (pad "F12" smd circle (at -10.795 -0.634 270) (size 0.64 0.64) (layers "B.Cu" "B.Mask")
      (net 9 "GND") (pinfunction "GND") (pintype "passive"))
    (pad "F13" smd circle (at -9.526 -0.634 270) (size 0.64 0.64) (layers "B.Cu" "B.Mask")
      (net 432 "unconnected-(J5C-HA12+-PadF13)") (pinfunction "HA12+") (pintype "passive+no_connect"))
    (pad "F14" smd circle (at -8.256 -0.634 270) (size 0.64 0.64) (layers "B.Cu" "B.Mask")
      (net 433 "unconnected-(J5C-HA12--PadF14)") (pinfunction "HA12-") (pintype "passive+no_connect"))
    (pad "F15" smd circle (at -6.986 -0.634 270) (size 0.64 0.64) (layers "B.Cu" "B.Mask")
      (net 9 "GND") (pinfunction "GND") (pintype "passive"))
    (pad "F16" smd circle (at -5.715 -0.634 270) (size 0.64 0.64) (layers "B.Cu" "B.Mask")
      (net 434 "unconnected-(J5C-HA15+-PadF16)") (pinfunction "HA15+") (pintype "passive+no_connect"))
    (pad "F17" smd circle (at -4.446 -0.634 270) (size 0.64 0.64) (layers "B.Cu" "B.Mask")
      (net 441 "unconnected-(J5C-HA15--PadF17)") (pinfunction "HA15-") (pintype "passive+no_connect"))
    (pad "F18" smd circle (at -3.175 -0.634 270) (size 0.64 0.64) (layers "B.Cu" "B.Mask")
      (net 9 "GND") (pinfunction "GND") (pintype "passive"))
    (pad "F19" smd circle (at -1.905 -0.634 270) (size 0.64 0.64) (layers "B.Cu" "B.Mask")
      (net 442 "unconnected-(J5C-HA19+-PadF19)") (pinfunction "HA19+") (pintype "passive+no_connect"))
    (pad "F20" smd circle (at -0.635 -0.634 270) (size 0.64 0.64) (layers "B.Cu" "B.Mask")
      (net 443 "unconnected-(J5C-HA19--PadF20)") (pinfunction "HA19-") (pintype "passive+no_connect"))
    (pad "F21" smd circle (at 0.634 -0.634 270) (size 0.64 0.64) (layers "B.Cu" "B.Mask")
      (net 9 "GND") (pinfunction "GND") (pintype "passive"))
    (pad "F22" smd circle (at 1.904 -0.634 270) (size 0.64 0.64) (layers "B.Cu" "B.Mask")
      (net 452 "unconnected-(J5C-HB02+-PadF22)") (pinfunction "HB02+") (pintype "passive+no_connect"))
    (pad "F23" smd circle (at 3.174 -0.634 270) (size 0.64 0.64) (layers "B.Cu" "B.Mask")
      (net 453 "unconnected-(J5C-HB02--PadF23)") (pinfunction "HB02-") (pintype "passive+no_connect"))
    (pad "F24" smd circle (at 4.445 -0.634 270) (size 0.64 0.64) (layers "B.Cu" "B.Mask")
      (net 9 "GND") (pinfunction "GND") (pintype "passive"))
    (pad "F25" smd circle (at 5.714 -0.634 270) (size 0.64 0.64) (layers "B.Cu" "B.Mask")
      (net 454 "unconnected-(J5C-HB04+-PadF25)") (pinfunction "HB04+") (pintype "passive+no_connect"))
    (pad "F26" smd circle (at 6.985 -0.634 270) (size 0.64 0.64) (layers "B.Cu" "B.Mask")
      (net 455 "unconnected-(J5C-HB04--PadF26)") (pinfunction "HB04-") (pintype "passive+no_connect"))
    (pad "F27" smd circle (at 8.255 -0.634 270) (size 0.64 0.64) (layers "B.Cu" "B.Mask")
      (net 9 "GND") (pinfunction "GND") (pintype "passive"))
    (pad "F28" smd circle (at 9.525 -0.634 270) (size 0.64 0.64) (layers "B.Cu" "B.Mask")
      (net 461 "unconnected-(J5C-HB08+-PadF28)") (pinfunction "HB08+") (pintype "passive+no_connect"))
    (pad "F29" smd circle (at 10.794 -0.634 270) (size 0.64 0.64) (layers "B.Cu" "B.Mask")
      (net 462 "unconnected-(J5C-HB08--PadF29)") (pinfunction "HB08-") (pintype "passive+no_connect"))
    (pad "F30" smd circle (at 12.064 -0.634 270) (size 0.64 0.64) (layers "B.Cu" "B.Mask")
      (net 9 "GND") (pinfunction "GND") (pintype "passive"))
    (pad "F31" smd circle (at 13.335 -0.634 270) (size 0.64 0.64) (layers "B.Cu" "B.Mask")
      (net 467 "unconnected-(J5C-HB12+-PadF31)") (pinfunction "HB12+") (pintype "passive+no_connect"))
    (pad "F32" smd circle (at 14.605 -0.634 270) (size 0.64 0.64) (layers "B.Cu" "B.Mask")
      (net 468 "unconnected-(J5C-HB12--PadF32)") (pinfunction "HB12-") (pintype "passive+no_connect"))
    (pad "F33" smd circle (at 15.874 -0.634 270) (size 0.64 0.64) (layers "B.Cu" "B.Mask")
      (net 9 "GND") (pinfunction "GND") (pintype "passive"))
    (pad "F34" smd circle (at 17.144 -0.634 270) (size 0.64 0.64) (layers "B.Cu" "B.Mask")
      (net 469 "unconnected-(J5C-HB16+-PadF34)") (pinfunction "HB16+") (pintype "passive+no_connect"))
    (pad "F35" smd circle (at 18.414 -0.634 270) (size 0.64 0.64) (layers "B.Cu" "B.Mask")
      (net 470 "unconnected-(J5C-HB16--PadF35)") (pinfunction "HB16-") (pintype "passive+no_connect"))
    (pad "F36" smd circle (at 19.684 -0.634 270) (size 0.64 0.64) (layers "B.Cu" "B.Mask")
      (net 9 "GND") (pinfunction "GND") (pintype "passive"))
    (pad "F37" smd circle (at 20.954 -0.634 270) (size 0.64 0.64) (layers "B.Cu" "B.Mask")
      (net 471 "unconnected-(J5C-HB20+-PadF37)") (pinfunction "HB20+") (pintype "passive+no_connect"))
    (pad "F38" smd circle (at 22.225 -0.634 270) (size 0.64 0.64) (layers "B.Cu" "B.Mask")
      (net 477 "unconnected-(J5C-HB20--PadF38)") (pinfunction "HB20-") (pintype "passive+no_connect"))
    (pad "F39" smd circle (at 23.495 -0.634 270) (size 0.64 0.64) (layers "B.Cu" "B.Mask")
      (net 9 "GND") (pinfunction "GND") (pintype "passive"))
    (pad "F40" smd circle (at 24.765 -0.634 270) (size 0.64 0.64) (layers "B.Cu" "B.Mask")
      (net 478 "unconnected-(J5C-VADJ-PadF40)") (pinfunction "VADJ") (pintype "passive+no_connect"))
    (pad "G1" smd circle (at -24.766 -1.904 270) (size 0.64 0.64) (layers "B.Cu" "B.Mask")
      (net 9 "GND") (pinfunction "GND") (pintype "passive"))
    (pad "G2" smd circle (at -23.496 -1.904 270) (size 0.64 0.64) (layers "B.Cu" "B.Mask")
      (net 484 "unconnected-(J5B-CLK1_{M2C}+-PadG2)") (pinfunction "CLK1_{M2C}+") (pintype "passive+no_connect"))
    (pad "G3" smd circle (at -22.226 -1.904 270) (size 0.64 0.64) (layers "B.Cu" "B.Mask")
      (net 485 "unconnected-(J5B-CLK1_{M2C}--PadG3)") (pinfunction "CLK1_{M2C}-") (pintype "passive+no_connect"))
    (pad "G4" smd circle (at -20.955 -1.904 270) (size 0.64 0.64) (layers "B.Cu" "B.Mask")
      (net 9 "GND") (pinfunction "GND") (pintype "passive"))
    (pad "G5" smd circle (at -19.685 -1.904 270) (size 0.64 0.64) (layers "B.Cu" "B.Mask")
      (net 9 "GND") (pinfunction "GND") (pintype "passive"))
    (pad "G6" smd circle (at -18.415 -1.904 270) (size 0.64 0.64) (layers "B.Cu" "B.Mask")
      (net 736 "EXT_LED_LINK") (pinfunction "LA00_{CC}+") (pintype "passive"))
    (pad "G7" smd circle (at -17.145 -1.904 270) (size 0.64 0.64) (layers "B.Cu" "B.Mask")
      (net 737 "EXT_LED_SPD") (pinfunction "LA00_{CC}-") (pintype "passive"))
    (pad "G8" smd circle (at -15.875 -1.904 270) (size 0.64 0.64) (layers "B.Cu" "B.Mask")
      (net 9 "GND") (pinfunction "GND") (pintype "passive"))
    (pad "G9" smd circle (at -14.606 -1.904 270) (size 0.64 0.64) (layers "B.Cu" "B.Mask")
      (net 738 "EXT_ETH2_P") (pinfunction "LA03+") (pintype "passive"))
    (pad "G10" smd circle (at -13.336 -1.904 270) (size 0.64 0.64) (layers "B.Cu" "B.Mask")
      (net 739 "EXT_ETH2_N") (pinfunction "LA03-") (pintype "passive"))
    (pad "G11" smd circle (at -12.065 -1.904 270) (size 0.64 0.64) (layers "B.Cu" "B.Mask")
      (net 9 "GND") (pinfunction "GND") (pintype "passive"))
    (pad "G12" smd circle (at -10.795 -1.904 270) (size 0.64 0.64) (layers "B.Cu" "B.Mask")
      (net 740 "EXT_ETH4_P") (pinfunction "LA08+") (pintype "passive"))
    (pad "G13" smd circle (at -9.526 -1.904 270) (size 0.64 0.64) (layers "B.Cu" "B.Mask")
      (net 741 "EXT_ETH4_N") (pinfunction "LA08-") (pintype "passive"))
    (pad "G14" smd circle (at -8.256 -1.904 270) (size 0.64 0.64) (layers "B.Cu" "B.Mask")
      (net 9 "GND") (pinfunction "GND") (pintype "passive"))
    (pad "G15" smd circle (at -6.986 -1.904 270) (size 0.64 0.64) (layers "B.Cu" "B.Mask")
      (net 486 "unconnected-(J5B-LA12+-PadG15)") (pinfunction "LA12+") (pintype "passive+no_connect"))
    (pad "G16" smd circle (at -5.715 -1.904 270) (size 0.64 0.64) (layers "B.Cu" "B.Mask")
      (net 487 "unconnected-(J5B-LA12--PadG16)") (pinfunction "LA12-") (pintype "passive+no_connect"))
    (pad "G17" smd circle (at -4.446 -1.904 270) (size 0.64 0.64) (layers "B.Cu" "B.Mask")
      (net 9 "GND") (pinfunction "GND") (pintype "passive"))
    (pad "G18" smd circle (at -3.175 -1.904 270) (size 0.64 0.64) (layers "B.Cu" "B.Mask")
      (net 407 "FMC_IO_2_P") (pinfunction "LA16+") (pintype "passive"))
    (pad "G19" smd circle (at -1.905 -1.904 270) (size 0.64 0.64) (layers "B.Cu" "B.Mask")
      (net 416 "FMC_IO_2_N") (pinfunction "LA16-") (pintype "passive"))
    (pad "G20" smd circle (at -0.635 -1.904 270) (size 0.64 0.64) (layers "B.Cu" "B.Mask")
      (net 9 "GND") (pinfunction "GND") (pintype "passive"))
    (pad "G21" smd circle (at 0.634 -1.904 270) (size 0.64 0.64) (layers "B.Cu" "B.Mask")
      (net 427 "FMC_IO_1_P") (pinfunction "LA20+") (pintype "passive"))
    (pad "G22" smd circle (at 1.904 -1.904 270) (size 0.64 0.64) (layers "B.Cu" "B.Mask")
      (net 417 "FMC_IO_1_N") (pinfunction "LA20-") (pintype "passive"))
    (pad "G23" smd circle (at 3.174 -1.904 270) (size 0.64 0.64) (layers "B.Cu" "B.Mask")
      (net 9 "GND") (pinfunction "GND") (pintype "passive"))
    (pad "G24" smd circle (at 4.445 -1.904 270) (size 0.64 0.64) (layers "B.Cu" "B.Mask")
      (net 437 "FMC_IO_6_P") (pinfunction "LA22+") (pintype "passive"))
    (pad "G25" smd circle (at 5.714 -1.904 270) (size 0.64 0.64) (layers "B.Cu" "B.Mask")
      (net 444 "FMC_IO_6_N") (pinfunction "LA22-") (pintype "passive"))
    (pad "G26" smd circle (at 6.985 -1.904 270) (size 0.64 0.64) (layers "B.Cu" "B.Mask")
      (net 9 "GND") (pinfunction "GND") (pintype "passive"))
    (pad "G27" smd circle (at 8.255 -1.904 270) (size 0.64 0.64) (layers "B.Cu" "B.Mask")
      (net 476 "FMC_IO_8_P") (pinfunction "LA25+") (pintype "passive"))
    (pad "G28" smd circle (at 9.525 -1.904 270) (size 0.64 0.64) (layers "B.Cu" "B.Mask")
      (net 460 "FMC_IO_8_N") (pinfunction "LA25-") (pintype "passive"))
    (pad "G29" smd circle (at 10.794 -1.904 270) (size 0.64 0.64) (layers "B.Cu" "B.Mask")
      (net 9 "GND") (pinfunction "GND") (pintype "passive"))
    (pad "G30" smd circle (at 12.064 -1.904 270) (size 0.64 0.64) (layers "B.Cu" "B.Mask")
      (net 515 "FMC_IO_9_P") (pinfunction "LA29+") (pintype "passive"))
    (pad "G31" smd circle (at 13.335 -1.904 270) (size 0.64 0.64) (layers "B.Cu" "B.Mask")
      (net 516 "FMC_IO_9_N") (pinfunction "LA29-") (pintype "passive"))
    (pad "G32" smd circle (at 14.605 -1.904 270) (size 0.64 0.64) (layers "B.Cu" "B.Mask")
      (net 9 "GND") (pinfunction "GND") (pintype "passive"))
    (pad "G33" smd circle (at 15.874 -1.904 270) (size 0.64 0.64) (layers "B.Cu" "B.Mask")
      (net 529 "FMC_IO_0") (pinfunction "LA31+") (pintype "passive"))
    (pad "G34" smd circle (at 17.144 -1.904 270) (size 0.64 0.64) (layers "B.Cu" "B.Mask")
      (net 488 "unconnected-(J5B-LA31--PadG34)") (pinfunction "LA31-") (pintype "passive+no_connect"))
    (pad "G35" smd circle (at 18.414 -1.904 270) (size 0.64 0.64) (layers "B.Cu" "B.Mask")
      (net 9 "GND") (pinfunction "GND") (pintype "passive"))
    (pad "G36" smd circle (at 19.684 -1.904 270) (size 0.64 0.64) (layers "B.Cu" "B.Mask")
      (net 489 "unconnected-(J5B-LA33+-PadG36)") (pinfunction "LA33+") (pintype "passive+no_connect"))
    (pad "G37" smd circle (at 20.954 -1.904 270) (size 0.64 0.64) (layers "B.Cu" "B.Mask")
      (net 494 "unconnected-(J5B-LA33--PadG37)") (pinfunction "LA33-") (pintype "passive+no_connect"))
    (pad "G38" smd circle (at 22.225 -1.904 270) (size 0.64 0.64) (layers "B.Cu" "B.Mask")
      (net 9 "GND") (pinfunction "GND") (pintype "passive"))
    (pad "G39" smd circle (at 23.495 -1.904 270) (size 0.64 0.64) (layers "B.Cu" "B.Mask")
      (net 495 "unconnected-(J5B-VADJ-PadG39)") (pinfunction "VADJ") (pintype "passive+no_connect"))
    (pad "G40" smd circle (at 24.765 -1.904 270) (size 0.64 0.64) (layers "B.Cu" "B.Mask")
      (net 9 "GND") (pinfunction "GND") (pintype "passive"))
    (pad "H1" smd circle (at -24.766 -3.174 270) (size 0.64 0.64) (layers "B.Cu" "B.Mask")
      (net 496 "Net-(J5B-VREF_{A_M2C})") (pinfunction "VREF_{A_M2C}") (pintype "passive"))
    (pad "H2" smd circle (at -23.496 -3.174 270) (size 0.64 0.64) (layers "B.Cu" "B.Mask")
      (net 751 "PRSNT_M2C") (pinfunction "~{PRSNT_{M2C}}") (pintype "passive"))
    (pad "H3" smd circle (at -22.226 -3.174 270) (size 0.64 0.64) (layers "B.Cu" "B.Mask")
      (net 9 "GND") (pinfunction "GND") (pintype "passive"))
    (pad "H4" smd circle (at -20.955 -3.174 270) (size 0.64 0.64) (layers "B.Cu" "B.Mask")
      (net 500 "unconnected-(J5B-CLK0_{M2C}+-PadH4)") (pinfunction "CLK0_{M2C}+") (pintype "passive+no_connect"))
    (pad "H5" smd circle (at -19.685 -3.174 270) (size 0.64 0.64) (layers "B.Cu" "B.Mask")
      (net 501 "unconnected-(J5B-CLK0_{M2C}--PadH5)") (pinfunction "CLK0_{M2C}-") (pintype "passive+no_connect"))
    (pad "H6" smd circle (at -18.415 -3.174 270) (size 0.64 0.64) (layers "B.Cu" "B.Mask")
      (net 9 "GND") (pinfunction "GND") (pintype "passive"))
    (pad "H7" smd circle (at -17.145 -3.174 270) (size 0.64 0.64) (layers "B.Cu" "B.Mask")
      (net 754 "EXT_ETH1_P") (pinfunction "LA02+") (pintype "passive"))
    (pad "H8" smd circle (at -15.875 -3.174 270) (size 0.64 0.64) (layers "B.Cu" "B.Mask")
      (net 755 "EXT_ETH1_N") (pinfunction "LA02-") (pintype "passive"))
    (pad "H9" smd circle (at -14.606 -3.174 270) (size 0.64 0.64) (layers "B.Cu" "B.Mask")
      (net 9 "GND") (pinfunction "GND") (pintype "passive"))
    (pad "H10" smd circle (at -13.336 -3.174 270) (size 0.64 0.64) (layers "B.Cu" "B.Mask")
      (net 756 "EXT_ETH3_P") (pinfunction "LA04+") (pintype "passive"))
    (pad "H11" smd circle (at -12.065 -3.174 270) (size 0.64 0.64) (layers "B.Cu" "B.Mask")
      (net 757 "EXT_ETH3_N") (pinfunction "LA04-") (pintype "passive"))
    (pad "H12" smd circle (at -10.795 -3.174 270) (size 0.64 0.64) (layers "B.Cu" "B.Mask")
      (net 9 "GND") (pinfunction "GND") (pintype "passive"))
    (pad "H13" smd circle (at -9.526 -3.174 270) (size 0.64 0.64) (layers "B.Cu" "B.Mask")
      (net 502 "unconnected-(J5B-LA07+-PadH13)") (pinfunction "LA07+") (pintype "passive+no_connect"))
    (pad "H14" smd circle (at -8.256 -3.174 270) (size 0.64 0.64) (layers "B.Cu" "B.Mask")
      (net 503 "unconnected-(J5B-LA07--PadH14)") (pinfunction "LA07-") (pintype "passive+no_connect"))
    (pad "H15" smd circle (at -6.986 -3.174 270) (size 0.64 0.64) (layers "B.Cu" "B.Mask")
      (net 9 "GND") (pinfunction "GND") (pintype "passive"))
    (pad "H16" smd circle (at -5.715 -3.174 270) (size 0.64 0.64) (layers "B.Cu" "B.Mask")
      (net 436 "FMC_IO_4_P") (pinfunction "LA11+") (pintype "passive"))
    (pad "H17" smd circle (at -4.446 -3.174 270) (size 0.64 0.64) (layers "B.Cu" "B.Mask")
      (net 426 "FMC_IO_4_N") (pinfunction "LA11-") (pintype "passive"))
    (pad "H18" smd circle (at -3.175 -3.174 270) (size 0.64 0.64) (layers "B.Cu" "B.Mask")
      (net 9 "GND") (pinfunction "GND") (pintype "passive"))
    (pad "H19" smd circle (at -1.905 -3.174 270) (size 0.64 0.64) (layers "B.Cu" "B.Mask")
      (net 425 "FMC_IO_3_P") (pinfunction "LA15+") (pintype "passive"))
    (pad "H20" smd circle (at -0.635 -3.174 270) (size 0.64 0.64) (layers "B.Cu" "B.Mask")
      (net 406 "FMC_IO_3_N") (pinfunction "LA15-") (pintype "passive"))
    (pad "H21" smd circle (at 0.634 -3.174 270) (size 0.64 0.64) (layers "B.Cu" "B.Mask")
      (net 9 "GND") (pinfunction "GND") (pintype "passive"))
    (pad "H22" smd circle (at 1.904 -3.174 270) (size 0.64 0.64) (layers "B.Cu" "B.Mask")
      (net 810 "FMC_IO_19_P") (pinfunction "LA19+") (pintype "passive"))
    (pad "H23" smd circle (at 3.174 -3.174 270) (size 0.64 0.64) (layers "B.Cu" "B.Mask")
      (net 528 "FMC_IO_19_N") (pinfunction "LA19-") (pintype "passive"))
    (pad "H24" smd circle (at 4.445 -3.174 270) (size 0.64 0.64) (layers "B.Cu" "B.Mask")
      (net 9 "GND") (pinfunction "GND") (pintype "passive"))
    (pad "H25" smd circle (at 5.714 -3.174 270) (size 0.64 0.64) (layers "B.Cu" "B.Mask")
      (net 448 "FMC_IO_10_P") (pinfunction "LA21+") (pintype "passive"))
    (pad "H26" smd circle (at 6.985 -3.174 270) (size 0.64 0.64) (layers "B.Cu" "B.Mask")
      (net 456 "FMC_IO_10_N") (pinfunction "LA21-") (pintype "passive"))
    (pad "H27" smd circle (at 8.255 -3.174 270) (size 0.64 0.64) (layers "B.Cu" "B.Mask")
      (net 9 "GND") (pinfunction "GND") (pintype "passive"))
    (pad "H28" smd circle (at 9.525 -3.174 270) (size 0.64 0.64) (layers "B.Cu" "B.Mask")
      (net 505 "FMC_IO_7_P") (pinfunction "LA24+") (pintype "passive"))
    (pad "H29" smd circle (at 10.794 -3.174 270) (size 0.64 0.64) (layers "B.Cu" "B.Mask")
      (net 490 "FMC_IO_7_N") (pinfunction "LA24-") (pintype "passive"))
    (pad "H30" smd circle (at 12.064 -3.174 270) (size 0.64 0.64) (layers "B.Cu" "B.Mask")
      (net 9 "GND") (pinfunction "GND") (pintype "passive"))
    (pad "H31" smd circle (at 13.335 -3.174 270) (size 0.64 0.64) (layers "B.Cu" "B.Mask")
      (net 504 "unconnected-(J5B-LA28+-PadH31)") (pinfunction "LA28+") (pintype "passive+no_connect"))
    (pad "H32" smd circle (at 14.605 -3.174 270) (size 0.64 0.64) (layers "B.Cu" "B.Mask")
      (net 508 "unconnected-(J5B-LA28--PadH32)") (pinfunction "LA28-") (pintype "passive+no_connect"))
    (pad "H33" smd circle (at 15.874 -3.174 270) (size 0.64 0.64) (layers "B.Cu" "B.Mask")
      (net 9 "GND") (pinfunction "GND") (pintype "passive"))
    (pad "H34" smd circle (at 17.144 -3.174 270) (size 0.64 0.64) (layers "B.Cu" "B.Mask")
      (net 509 "unconnected-(J5B-LA30+-PadH34)") (pinfunction "LA30+") (pintype "passive+no_connect"))
    (pad "H35" smd circle (at 18.414 -3.174 270) (size 0.64 0.64) (layers "B.Cu" "B.Mask")
      (net 510 "unconnected-(J5B-LA30--PadH35)") (pinfunction "LA30-") (pintype "passive+no_connect"))
    (pad "H36" smd circle (at 19.684 -3.174 270) (size 0.64 0.64) (layers "B.Cu" "B.Mask")
      (net 9 "GND") (pinfunction "GND") (pintype "passive"))
  )
)
